#ISCELL
  mstr_misc dns *
  *
#ISCELL
  mstr_symbols cad_note *
  *
#ISCELL
  mstr_symbols design_note *
  *
#ISCELL
  mstr_symbols intel_corp_bpage *
  *
#ISCELL
  mstr_standard offpage *
  page241_i1
#CELL
  w_hdl st220u10vdm-lgp *
  page241_i100
#CELL
  w_hdl sc22u16v5mx-4-gp *
  page241_i103
#CELL
  w_hdl sc22u16v5mx-4-gp *
  page241_i104
#CELL
  mstr_discrete res *
  page241_i11
#CELL
  mstr_discrete cap *
  page241_i12
#CELL
  mstr_discrete cap *
  page241_i14
#ISCELL
  mstr_symbols gnd *
  page241_i16
#CELL
  mstr_discrete res *
  page241_i18
#ISCELL
  mstr_symbols gnd *
  page241_i19
#CELL
  mstr_discrete cap *
  page241_i30
#ISCELL
  mstr_symbols gnd *
  page241_i31
#ISCELL
  mstr_symbols gnd *
  page241_i32
#CELL
  mstr_discrete res *
  page241_i37
#CELL
  mstr_discrete cap *
  page241_i39
#ISCELL
  mstr_symbols gnd *
  page241_i4
#ISCELL
  mstr_symbols gnd *
  page241_i40
#CELL
  mstr_discrete cap *
  page241_i41
#ISCELL
  mstr_standard offpage *
  page241_i48
#CELL
  mstr_discrete res *
  page241_i50
#CELL
  mstr_discrete res *
  page241_i51
#ISCELL
  mstr_symbols gnd *
  page241_i52
#CELL
  mstr_discrete cap *
  page241_i53
#CELL
  mstr_discrete res *
  page241_i54
#ISCELL
  mstr_symbols gnd *
  page241_i55
#CELL
  mstr_discrete cap *
  page241_i57
#CELL
  mstr_discrete res *
  page241_i58
#ISCELL
  mstr_symbols gnd *
  page241_i59
#CELL
  mstr_discrete cap *
  page241_i63
#ISCELL
  mstr_symbols gnd *
  page241_i64
#ISCELL
  mstr_symbols p5v_stby *
  page241_i69
#ISCELL
  mstr_symbols p12v_stby *
  page241_i71
#CELL
  mstr_discrete res *
  page241_i78
#CELL
  mstr_discrete ferrite *
  page241_i82
#CELL
  mstr_vreg tps54821 *
  page241_i83
#ISCELL
  mstr_symbols p5v_stby *
  page241_i85
#ISCELL
  mstr_symbols gnd *
  page241_i86
#CELL
  mstr_discrete res *
  page241_i89
#CELL
  mstr_discrete res *
  page241_i9
#CELL
  mstr_discrete inductor *
  page241_i90
#CELL
  mstr_discrete res *
  page241_i91
#CELL
  w_hdl sc22u16v5mx-4-gp *
  page241_i92
#ISCELL
  mstr_symbols gnd *
  page241_i93
#ISCELL
  mstr_symbols gnd *
  page241_i94
#CELL
  w_hdl sc22u16v5mx-4-gp *
  page241_i95
#CELL
  w_hdl sc22u16v5mx-4-gp *
  page241_i96
#ISCELL
  mstr_symbols gnd *
  page241_i97
#CELL
  w_hdl sc22u16v5mx-4-gp *
  page241_i98
#ISCELL
  mstr_symbols gnd *
  page241_i99
